(kicad_pcb
	(version 20260206)
	(generator "pcbnew")
	(generator_version "10.0")
	(general
		(thickness 1.6)
		(legacy_teardrops no)
	)
	(paper "A4")
	(title_block
		(title "Wiwynn_Tioga_Pass_MB.brd")
		(comment 1 "Tioga Pass / footprints 1744-1748 of 4770")
	)
	(layers
		(0 "F.Cu" signal "TOP")
		(4 "In1.Cu" signal "L2GND")
		(6 "In2.Cu" signal "L3")
		(8 "In3.Cu" signal "L4GND")
		(10 "In4.Cu" signal "L5")
		(12 "In5.Cu" signal "L6GND")
		(14 "In6.Cu" signal "L7VCC")
		(16 "In7.Cu" signal "L8VCC")
		(18 "In8.Cu" signal "L9GND")
		(20 "In9.Cu" signal "L10")
		(22 "In10.Cu" signal "L11GND")
		(24 "In11.Cu" signal "L12")
		(26 "In12.Cu" signal "L13GND")
		(2 "B.Cu" signal "BOTTOM")
		(9 "F.Adhes" user "F.Adhesive")
		(11 "B.Adhes" user "B.Adhesive")
		(13 "F.Paste" user "Package Geometry/Pastemask Top")
		(15 "B.Paste" user "Package Geometry/Pastemask Bottom")
		(5 "F.SilkS" user "Ref Des/Silkscreen Top")
		(7 "B.SilkS" user "Ref Des/Silkscreen Bottom")
		(1 "F.Mask" user "Board Geometry/Soldermask Top")
		(3 "B.Mask" user "Board Geometry/Soldermask Bottom")
		(17 "Dwgs.User" user "User.Drawings")
		(19 "Cmts.User" user "User.Comments")
		(21 "Eco1.User" user "User.Eco1")
		(23 "Eco2.User" user "User.Eco2")
		(25 "Edge.Cuts" user "Board Geometry/Outline")
		(27 "Margin" user)
		(31 "F.CrtYd" user "Package Geometry/Place Bound Top")
		(29 "B.CrtYd" user "Package Geometry/Place Bound Bottom")
		(35 "F.Fab" user "Ref Des/Assembly Top")
		(33 "B.Fab" user "Ref Des/Assembly Bottom")
	)
	(footprint ""
		(layer "F.Cu")
		(at 457.83119 -35.569906)
		(property "Reference" "R8B25"
			(at 0 0 0)
			(layer "F.SilkS")
			(hide yes)
			(effects
				(font
					(size 1.27 1.27)
				)
			)
		)
		(property "Value" ""
			(at 0 0 0)
			(layer "F.Fab")
			(effects
				(font
					(size 1.27 1.27)
				)
			)
		)
		(duplicate_pad_numbers_are_jumpers no)
		(fp_poly
			(pts
				(xy -0.2794 -0.1016) (xy 0.2794 -0.1016) (xy 0.2794 0.9906) (xy -0.2794 0.9906)
			)
			(stroke
				(width 0)
				(type default)
			)
			(fill no)
			(layer "F.CrtYd")
		)
		(fp_line
			(start -0.2794 -0.1016)
			(end -0.2794 0.9906)
			(stroke
				(width 0.1)
				(type default)
			)
			(layer "F.Fab")
		)
		(fp_line
			(start -0.2794 0.9906)
			(end 0.2794 0.9906)
			(stroke
				(width 0.1)
				(type default)
			)
			(layer "F.Fab")
		)
		(fp_line
			(start 0.2794 -0.1016)
			(end -0.2794 -0.1016)
			(stroke
				(width 0.1)
				(type default)
			)
			(layer "F.Fab")
		)
		(fp_line
			(start 0.2794 0.9906)
			(end 0.2794 -0.1016)
			(stroke
				(width 0.1)
				(type default)
			)
			(layer "F.Fab")
		)
		(pad "1" smd rect
			(at 0 0)
			(size 0.508 0.508)
			(layers "F.Cu" "F.Mask" "F.Paste")
			(net "P3V3_STBY")
		)
		(pad "2" smd rect
			(at 0 0.889)
			(size 0.508 0.508)
			(layers "F.Cu" "F.Mask" "F.Paste")
			(net "FM_BMC_HEARTBEAT_N")
		)
		(zone
			(layer "F.Cu")
			(hatch none 0.5)
			(connect_pads
				(clearance 0)
			)
			(min_thickness 0.25)
			(keepout
				(tracks allowed)
				(vias not_allowed)
				(pads allowed)
				(copperpour not_allowed)
				(footprints allowed)
			)
			(placement
				(enabled no)
				(sheetname "")
			)
			(fill
				(thermal_gap 0.5)
				(thermal_bridge_width 0.5)
				(island_removal_mode 0)
			)
			(polygon
				(pts
					(xy 457.57719 -35.315906) (xy 458.08519 -35.315906) (xy 458.08519 -34.934906) (xy 457.57719 -34.934906)
				)
			)
		)
		(zone
			(layer "F.Cu")
			(hatch none 0.5)
			(connect_pads
				(clearance 0)
			)
			(min_thickness 0.25)
			(keepout
				(tracks not_allowed)
				(vias allowed)
				(pads allowed)
				(copperpour not_allowed)
				(footprints allowed)
			)
			(placement
				(enabled no)
				(sheetname "")
			)
			(fill
				(thermal_gap 0.5)
				(thermal_bridge_width 0.5)
				(island_removal_mode 0)
			)
			(polygon
				(pts
					(xy 457.57719 -34.934906) (xy 458.08519 -34.934906) (xy 458.08519 -35.315906) (xy 457.57719 -35.315906)
				)
			)
		)
	)
	(footprint ""
		(layer "F.Cu")
		(at 347.975936 -140.575538 -90)
		(property "Reference" "C7A21"
			(at 0 0 270)
			(layer "F.SilkS")
			(hide yes)
			(effects
				(font
					(size 1.27 1.27)
				)
			)
		)
		(property "Value" ""
			(at 0 0 270)
			(layer "F.Fab")
			(effects
				(font
					(size 1.27 1.27)
				)
			)
		)
		(duplicate_pad_numbers_are_jumpers no)
		(fp_poly
			(pts
				(xy 0.3048 -0.1016) (xy 0.3048 0.9906) (xy -0.3048 0.9906) (xy -0.3048 -0.1016)
			)
			(stroke
				(width 0)
				(type default)
			)
			(fill no)
			(layer "F.CrtYd")
		)
		(fp_line
			(start -0.3048 0.9906)
			(end 0.3048 0.9906)
			(stroke
				(width 0.1)
				(type default)
			)
			(layer "F.Fab")
		)
		(fp_line
			(start 0.3048 0.9906)
			(end 0.3048 -0.1016)
			(stroke
				(width 0.1)
				(type default)
			)
			(layer "F.Fab")
		)
		(fp_line
			(start -0.3048 -0.1016)
			(end -0.3048 0.9906)
			(stroke
				(width 0.1)
				(type default)
			)
			(layer "F.Fab")
		)
		(fp_line
			(start 0.3048 -0.1016)
			(end -0.3048 -0.1016)
			(stroke
				(width 0.1)
				(type default)
			)
			(layer "F.Fab")
		)
		(pad "1" smd rect
			(at 0 0 270)
			(size 0.508 0.508)
			(layers "F.Cu" "F.Mask" "F.Paste")
			(net "VR_FET_SW_P12V_STBY_PVDDQ_DEF")
		)
		(pad "2" smd rect
			(at 0 0.889 270)
			(size 0.508 0.508)
			(layers "F.Cu" "F.Mask" "F.Paste")
			(net "GND")
		)
		(zone
			(layer "F.Cu")
			(hatch none 0.5)
			(connect_pads
				(clearance 0)
			)
			(min_thickness 0.25)
			(keepout
				(tracks not_allowed)
				(vias allowed)
				(pads allowed)
				(copperpour not_allowed)
				(footprints allowed)
			)
			(placement
				(enabled no)
				(sheetname "")
			)
			(fill
				(thermal_gap 0.5)
				(thermal_bridge_width 0.5)
				(island_removal_mode 0)
			)
			(polygon
				(pts
					(xy 347.340936 -140.829538) (xy 347.340936 -140.321538) (xy 347.721936 -140.321538) (xy 347.721936 -140.829538)
				)
			)
		)
		(zone
			(layer "F.Cu")
			(hatch none 0.5)
			(connect_pads
				(clearance 0)
			)
			(min_thickness 0.25)
			(keepout
				(tracks allowed)
				(vias not_allowed)
				(pads allowed)
				(copperpour not_allowed)
				(footprints allowed)
			)
			(placement
				(enabled no)
				(sheetname "")
			)
			(fill
				(thermal_gap 0.5)
				(thermal_bridge_width 0.5)
				(island_removal_mode 0)
			)
			(polygon
				(pts
					(xy 347.721936 -140.829538) (xy 347.721936 -140.321538) (xy 347.340936 -140.321538) (xy 347.340936 -140.829538)
				)
			)
		)
	)
	(footprint ""
		(layer "F.Cu")
		(at 182.6514 -146.685)
		(property "Reference" "C4A11"
			(at 0 0 0)
			(layer "F.SilkS")
			(hide yes)
			(effects
				(font
					(size 1.27 1.27)
				)
			)
		)
		(property "Value" ""
			(at 0 0 0)
			(layer "F.Fab")
			(effects
				(font
					(size 1.27 1.27)
				)
			)
		)
		(duplicate_pad_numbers_are_jumpers no)
		(fp_poly
			(pts
				(xy -0.4953 -0.2032) (xy 0.4953 -0.2032) (xy 0.4953 1.6002) (xy -0.4953 1.6002)
			)
			(stroke
				(width 0)
				(type default)
			)
			(fill no)
			(layer "F.CrtYd")
		)
		(fp_line
			(start -0.4953 -0.2032)
			(end 0.4953 -0.2032)
			(stroke
				(width 0.1)
				(type default)
			)
			(layer "F.Fab")
		)
		(fp_line
			(start -0.4953 1.6002)
			(end -0.4953 -0.2032)
			(stroke
				(width 0.1)
				(type default)
			)
			(layer "F.Fab")
		)
		(fp_line
			(start 0.4953 -0.2032)
			(end 0.4953 1.6002)
			(stroke
				(width 0.1)
				(type default)
			)
			(layer "F.Fab")
		)
		(fp_line
			(start 0.4953 1.6002)
			(end -0.4953 1.6002)
			(stroke
				(width 0.1)
				(type default)
			)
			(layer "F.Fab")
		)
		(pad "1" smd rect
			(at 0 0)
			(size 0.762 0.889)
			(layers "F.Cu" "F.Mask" "F.Paste")
			(net "VSENSE_PVDDQ_DEF_VTT")
		)
		(pad "2" smd rect
			(at 0 1.397)
			(size 0.762 0.889)
			(layers "F.Cu" "F.Mask" "F.Paste")
			(net "GND")
		)
		(zone
			(layer "F.Cu")
			(hatch none 0.5)
			(connect_pads
				(clearance 0)
			)
			(min_thickness 0.25)
			(keepout
				(tracks not_allowed)
				(vias allowed)
				(pads allowed)
				(copperpour not_allowed)
				(footprints allowed)
			)
			(placement
				(enabled no)
				(sheetname "")
			)
			(fill
				(thermal_gap 0.5)
				(thermal_bridge_width 0.5)
				(island_removal_mode 0)
			)
			(polygon
				(pts
					(xy 182.2704 -146.2405) (xy 183.0324 -146.2405) (xy 183.0324 -145.7325) (xy 182.2704 -145.7325)
				)
			)
		)
	)
	(footprint ""
		(layer "F.Cu")
		(at 278.868124 -71.714614 180)
		(property "Reference" "C6D9"
			(at 0 0 180)
			(layer "F.SilkS")
			(hide yes)
			(effects
				(font
					(size 1.27 1.27)
				)
			)
		)
		(property "Value" ""
			(at 0 0 180)
			(layer "F.Fab")
			(effects
				(font
					(size 1.27 1.27)
				)
			)
		)
		(duplicate_pad_numbers_are_jumpers no)
		(fp_poly
			(pts
				(xy -0.4953 -0.2032) (xy 0.4953 -0.2032) (xy 0.4953 1.6002) (xy -0.4953 1.6002)
			)
			(stroke
				(width 0)
				(type default)
			)
			(fill no)
			(layer "F.CrtYd")
		)
		(fp_line
			(start 0.4953 1.6002)
			(end -0.4953 1.6002)
			(stroke
				(width 0.1)
				(type default)
			)
			(layer "F.Fab")
		)
		(fp_line
			(start 0.4953 -0.2032)
			(end 0.4953 1.6002)
			(stroke
				(width 0.1)
				(type default)
			)
			(layer "F.Fab")
		)
		(fp_line
			(start -0.4953 1.6002)
			(end -0.4953 -0.2032)
			(stroke
				(width 0.1)
				(type default)
			)
			(layer "F.Fab")
		)
		(fp_line
			(start -0.4953 -0.2032)
			(end 0.4953 -0.2032)
			(stroke
				(width 0.1)
				(type default)
			)
			(layer "F.Fab")
		)
		(pad "1" smd rect
			(at 0 0 180)
			(size 0.762 0.889)
			(layers "F.Cu" "F.Mask" "F.Paste")
			(net "PVCCIO_CPU0")
		)
		(pad "2" smd rect
			(at 0 1.397 180)
			(size 0.762 0.889)
			(layers "F.Cu" "F.Mask" "F.Paste")
			(net "GND")
		)
		(zone
			(layer "F.Cu")
			(hatch none 0.5)
			(connect_pads
				(clearance 0)
			)
			(min_thickness 0.25)
			(keepout
				(tracks not_allowed)
				(vias allowed)
				(pads allowed)
				(copperpour not_allowed)
				(footprints allowed)
			)
			(placement
				(enabled no)
				(sheetname "")
			)
			(fill
				(thermal_gap 0.5)
				(thermal_bridge_width 0.5)
				(island_removal_mode 0)
			)
			(polygon
				(pts
					(xy 279.249124 -72.159114) (xy 278.487124 -72.159114) (xy 278.487124 -72.667114) (xy 279.249124 -72.667114)
				)
			)
		)
	)
	(footprint ""
		(layer "F.Cu")
		(at 268.1732 -79.6036 180)
		(property "Reference" "C5D19"
			(at 0 0 180)
			(layer "F.SilkS")
			(hide yes)
			(effects
				(font
					(size 1.27 1.27)
				)
			)
		)
		(property "Value" ""
			(at 0 0 180)
			(layer "F.Fab")
			(effects
				(font
					(size 1.27 1.27)
				)
			)
		)
		(duplicate_pad_numbers_are_jumpers no)
		(fp_poly
			(pts
				(xy -0.4953 -0.2032) (xy 0.4953 -0.2032) (xy 0.4953 1.6002) (xy -0.4953 1.6002)
			)
			(stroke
				(width 0)
				(type default)
			)
			(fill no)
			(layer "F.CrtYd")
		)
		(fp_line
			(start 0.4953 1.6002)
			(end -0.4953 1.6002)
			(stroke
				(width 0.1)
				(type default)
			)
			(layer "F.Fab")
		)
		(fp_line
			(start 0.4953 -0.2032)
			(end 0.4953 1.6002)
			(stroke
				(width 0.1)
				(type default)
			)
			(layer "F.Fab")
		)
		(fp_line
			(start -0.4953 1.6002)
			(end -0.4953 -0.2032)
			(stroke
				(width 0.1)
				(type default)
			)
			(layer "F.Fab")
		)
		(fp_line
			(start -0.4953 -0.2032)
			(end 0.4953 -0.2032)
			(stroke
				(width 0.1)
				(type default)
			)
			(layer "F.Fab")
		)
		(pad "1" smd rect
			(at 0 0 180)
			(size 0.762 0.889)
			(layers "F.Cu" "F.Mask" "F.Paste")
			(net "PVCCIN_CPU0")
		)
		(pad "2" smd rect
			(at 0 1.397 180)
			(size 0.762 0.889)
			(layers "F.Cu" "F.Mask" "F.Paste")
			(net "GND")
		)
		(zone
			(layer "F.Cu")
			(hatch none 0.5)
			(connect_pads
				(clearance 0)
			)
			(min_thickness 0.25)
			(keepout
				(tracks not_allowed)
				(vias allowed)
				(pads allowed)
				(copperpour not_allowed)
				(footprints allowed)
			)
			(placement
				(enabled no)
				(sheetname "")
			)
			(fill
				(thermal_gap 0.5)
				(thermal_bridge_width 0.5)
				(island_removal_mode 0)
			)
			(polygon
				(pts
					(xy 268.5542 -80.0481) (xy 267.7922 -80.0481) (xy 267.7922 -80.5561) (xy 268.5542 -80.5561)
				)
			)
		)
	)
)
